(kicad_pcb
	(version 20260206)
	(generator "pcbnew")
	(generator_version "10.0")
	(general
		(thickness 1.6)
		(legacy_teardrops no)
	)
	(paper "A4")
	(title_block
		(title "04192023_DAF0TMB3IC0_F0TG_MB_C_brd_V02_OCP.brd")
		(comment 1 "Grand Teton / footprints 2753-2758 of 8354")
	)
	(layers
		(0 "F.Cu" signal "TOP")
		(4 "In1.Cu" signal "GND")
		(6 "In2.Cu" signal "IN1")
		(8 "In3.Cu" signal "GND1")
		(10 "In4.Cu" signal "IN2")
		(12 "In5.Cu" signal "GND2")
		(14 "In6.Cu" signal "IN3")
		(16 "In7.Cu" signal "GND3")
		(18 "In8.Cu" signal "VCC")
		(20 "In9.Cu" signal "VCC1")
		(22 "In10.Cu" signal "GND4")
		(24 "In11.Cu" signal "IN4")
		(26 "In12.Cu" signal "GND5")
		(28 "In13.Cu" signal "IN5")
		(30 "In14.Cu" signal "GND6")
		(32 "In15.Cu" signal "IN6")
		(34 "In16.Cu" signal "GND7")
		(2 "B.Cu" signal "BOTTOM")
		(9 "F.Adhes" user "F.Adhesive")
		(11 "B.Adhes" user "B.Adhesive")
		(13 "F.Paste" user "Package Geometry/Pastemask Top")
		(15 "B.Paste" user "Package Geometry/Pastemask Bottom")
		(5 "F.SilkS" user "Ref Des/Silkscreen Top")
		(7 "B.SilkS" user "Ref Des/Silkscreen Bottom")
		(1 "F.Mask" user "Board Geometry/Soldermask Top")
		(3 "B.Mask" user "Board Geometry/Soldermask Bottom")
		(17 "Dwgs.User" user "User.Drawings")
		(19 "Cmts.User" user "User.Comments")
		(21 "Eco1.User" user "User.Eco1")
		(23 "Eco2.User" user "User.Eco2")
		(25 "Edge.Cuts" user "Board Geometry/Outline")
		(27 "Margin" user)
		(31 "F.CrtYd" user "Package Geometry/Place Bound Top")
		(29 "B.CrtYd" user "Package Geometry/Place Bound Bottom")
		(35 "F.Fab" user "Ref Des/Assembly Top")
		(33 "B.Fab" user "Ref Des/Assembly Bottom")
	)
	(footprint ""
		(layer "F.Cu")
		(at 442.340238 -364.49127)
		(property "Reference" "PC6003"
			(at 0 0 0)
			(layer "F.SilkS")
			(hide yes)
			(effects
				(font
					(size 1.27 1.27)
				)
			)
		)
		(property "Value" ""
			(at 0 0 0)
			(layer "F.Fab")
			(effects
				(font
					(size 1.27 1.27)
				)
			)
		)
		(duplicate_pad_numbers_are_jumpers no)
		(fp_line
			(start -0.7874 -0.4064)
			(end 0.7874 -0.4064)
			(stroke
				(width 0.1524)
				(type default)
			)
			(layer "F.SilkS")
		)
		(fp_line
			(start -0.7874 0.4064)
			(end -0.7874 -0.4064)
			(stroke
				(width 0.1524)
				(type default)
			)
			(layer "F.SilkS")
		)
		(fp_line
			(start 0.7874 -0.4064)
			(end 0.7874 0.4064)
			(stroke
				(width 0.1524)
				(type default)
			)
			(layer "F.SilkS")
		)
		(fp_line
			(start 0.7874 0.4064)
			(end -0.7874 0.4064)
			(stroke
				(width 0.1524)
				(type default)
			)
			(layer "F.SilkS")
		)
		(fp_line
			(start -0.67945 -0.305054)
			(end -0.12065 -0.305054)
			(stroke
				(width 0.1)
				(type default)
			)
			(layer "F.Fab")
		)
		(fp_line
			(start -0.67945 0.3048)
			(end -0.67945 -0.305054)
			(stroke
				(width 0.1)
				(type default)
			)
			(layer "F.Fab")
		)
		(fp_line
			(start -0.12065 -0.305054)
			(end -0.12065 -0.2794)
			(stroke
				(width 0.1)
				(type default)
			)
			(layer "F.Fab")
		)
		(fp_line
			(start -0.12065 -0.2794)
			(end 0.12065 -0.2794)
			(stroke
				(width 0.1)
				(type default)
			)
			(layer "F.Fab")
		)
		(fp_line
			(start -0.12065 0.2794)
			(end -0.12065 0.3048)
			(stroke
				(width 0.1)
				(type default)
			)
			(layer "F.Fab")
		)
		(fp_line
			(start -0.12065 0.3048)
			(end -0.67945 0.3048)
			(stroke
				(width 0.1)
				(type default)
			)
			(layer "F.Fab")
		)
		(fp_line
			(start 0.120396 0.2794)
			(end -0.12065 0.2794)
			(stroke
				(width 0.1)
				(type default)
			)
			(layer "F.Fab")
		)
		(fp_line
			(start 0.120396 0.3048)
			(end 0.120396 0.2794)
			(stroke
				(width 0.1)
				(type default)
			)
			(layer "F.Fab")
		)
		(fp_line
			(start 0.12065 -0.3048)
			(end 0.67945 -0.3048)
			(stroke
				(width 0.1)
				(type default)
			)
			(layer "F.Fab")
		)
		(fp_line
			(start 0.12065 -0.2794)
			(end 0.12065 -0.3048)
			(stroke
				(width 0.1)
				(type default)
			)
			(layer "F.Fab")
		)
		(fp_line
			(start 0.67945 -0.3048)
			(end 0.67945 0.3048)
			(stroke
				(width 0.1)
				(type default)
			)
			(layer "F.Fab")
		)
		(fp_line
			(start 0.67945 0.3048)
			(end 0.120396 0.3048)
			(stroke
				(width 0.1)
				(type default)
			)
			(layer "F.Fab")
		)
		(pad "1" smd circle
			(at -0.40005 0)
			(size 0 0)
			(layers "F.Cu" "F.Mask" "F.Paste")
			(net "P12V_AUX")
		)
		(pad "2" smd circle
			(at 0.40005 0)
			(size 0 0)
			(layers "F.Cu" "F.Mask" "F.Paste")
			(net "GND")
		)
	)
	(footprint ""
		(layer "F.Cu")
		(at 289.589718 -423.456608 90)
		(property "Reference" "R6802"
			(at 0 0 90)
			(layer "F.SilkS")
			(hide yes)
			(effects
				(font
					(size 1.27 1.27)
				)
			)
		)
		(property "Value" ""
			(at 0 0 90)
			(layer "F.Fab")
			(effects
				(font
					(size 1.27 1.27)
				)
			)
		)
		(duplicate_pad_numbers_are_jumpers no)
		(fp_line
			(start 0.7874 -0.4064)
			(end 0.7874 0.4064)
			(stroke
				(width 0.1524)
				(type default)
			)
			(layer "F.SilkS")
		)
		(fp_line
			(start -0.7874 -0.4064)
			(end 0.7874 -0.4064)
			(stroke
				(width 0.1524)
				(type default)
			)
			(layer "F.SilkS")
		)
		(fp_line
			(start 0.7874 0.4064)
			(end -0.7874 0.4064)
			(stroke
				(width 0.1524)
				(type default)
			)
			(layer "F.SilkS")
		)
		(fp_line
			(start -0.7874 0.4064)
			(end -0.7874 -0.4064)
			(stroke
				(width 0.1524)
				(type default)
			)
			(layer "F.SilkS")
		)
		(fp_line
			(start -0.12065 -0.305054)
			(end -0.12065 -0.2794)
			(stroke
				(width 0.1)
				(type default)
			)
			(layer "F.Fab")
		)
		(fp_line
			(start -0.67945 -0.305054)
			(end -0.12065 -0.305054)
			(stroke
				(width 0.1)
				(type default)
			)
			(layer "F.Fab")
		)
		(fp_line
			(start 0.67945 -0.3048)
			(end 0.67945 0.3048)
			(stroke
				(width 0.1)
				(type default)
			)
			(layer "F.Fab")
		)
		(fp_line
			(start 0.12065 -0.3048)
			(end 0.67945 -0.3048)
			(stroke
				(width 0.1)
				(type default)
			)
			(layer "F.Fab")
		)
		(fp_line
			(start 0.12065 -0.2794)
			(end 0.12065 -0.3048)
			(stroke
				(width 0.1)
				(type default)
			)
			(layer "F.Fab")
		)
		(fp_line
			(start -0.12065 -0.2794)
			(end 0.12065 -0.2794)
			(stroke
				(width 0.1)
				(type default)
			)
			(layer "F.Fab")
		)
		(fp_line
			(start 0.120396 0.2794)
			(end -0.12065 0.2794)
			(stroke
				(width 0.1)
				(type default)
			)
			(layer "F.Fab")
		)
		(fp_line
			(start -0.12065 0.2794)
			(end -0.12065 0.3048)
			(stroke
				(width 0.1)
				(type default)
			)
			(layer "F.Fab")
		)
		(fp_line
			(start 0.67945 0.3048)
			(end 0.120396 0.3048)
			(stroke
				(width 0.1)
				(type default)
			)
			(layer "F.Fab")
		)
		(fp_line
			(start 0.120396 0.3048)
			(end 0.120396 0.2794)
			(stroke
				(width 0.1)
				(type default)
			)
			(layer "F.Fab")
		)
		(fp_line
			(start -0.12065 0.3048)
			(end -0.67945 0.3048)
			(stroke
				(width 0.1)
				(type default)
			)
			(layer "F.Fab")
		)
		(fp_line
			(start -0.67945 0.3048)
			(end -0.67945 -0.305054)
			(stroke
				(width 0.1)
				(type default)
			)
			(layer "F.Fab")
		)
		(pad "1" smd circle
			(at -0.40005 0 90)
			(size 0 0)
			(layers "F.Cu" "F.Mask" "F.Paste")
			(net "FM_9ZXL045_P0_3_OE_N")
		)
		(pad "2" smd circle
			(at 0.40005 0 90)
			(size 0 0)
			(layers "F.Cu" "F.Mask" "F.Paste")
			(net "GND")
		)
	)
	(footprint ""
		(layer "F.Cu")
		(at 105.960164 -259.355336)
		(property "Reference" "C2278"
			(at 0 0 0)
			(layer "F.SilkS")
			(hide yes)
			(effects
				(font
					(size 1.27 1.27)
				)
			)
		)
		(property "Value" ""
			(at 0 0 0)
			(layer "F.Fab")
			(effects
				(font
					(size 1.27 1.27)
				)
			)
		)
		(duplicate_pad_numbers_are_jumpers no)
		(fp_line
			(start -0.7874 -0.4064)
			(end 0.7874 -0.4064)
			(stroke
				(width 0.1524)
				(type default)
			)
			(layer "F.SilkS")
		)
		(fp_line
			(start -0.7874 0.4064)
			(end -0.7874 -0.4064)
			(stroke
				(width 0.1524)
				(type default)
			)
			(layer "F.SilkS")
		)
		(fp_line
			(start 0.7874 -0.4064)
			(end 0.7874 0.4064)
			(stroke
				(width 0.1524)
				(type default)
			)
			(layer "F.SilkS")
		)
		(fp_line
			(start 0.7874 0.4064)
			(end -0.7874 0.4064)
			(stroke
				(width 0.1524)
				(type default)
			)
			(layer "F.SilkS")
		)
		(fp_line
			(start -0.67945 -0.305054)
			(end -0.12065 -0.305054)
			(stroke
				(width 0.1)
				(type default)
			)
			(layer "F.Fab")
		)
		(fp_line
			(start -0.67945 0.3048)
			(end -0.67945 -0.305054)
			(stroke
				(width 0.1)
				(type default)
			)
			(layer "F.Fab")
		)
		(fp_line
			(start -0.12065 -0.305054)
			(end -0.12065 -0.2794)
			(stroke
				(width 0.1)
				(type default)
			)
			(layer "F.Fab")
		)
		(fp_line
			(start -0.12065 -0.2794)
			(end 0.12065 -0.2794)
			(stroke
				(width 0.1)
				(type default)
			)
			(layer "F.Fab")
		)
		(fp_line
			(start -0.12065 0.2794)
			(end -0.12065 0.3048)
			(stroke
				(width 0.1)
				(type default)
			)
			(layer "F.Fab")
		)
		(fp_line
			(start -0.12065 0.3048)
			(end -0.67945 0.3048)
			(stroke
				(width 0.1)
				(type default)
			)
			(layer "F.Fab")
		)
		(fp_line
			(start 0.120396 0.2794)
			(end -0.12065 0.2794)
			(stroke
				(width 0.1)
				(type default)
			)
			(layer "F.Fab")
		)
		(fp_line
			(start 0.120396 0.3048)
			(end 0.120396 0.2794)
			(stroke
				(width 0.1)
				(type default)
			)
			(layer "F.Fab")
		)
		(fp_line
			(start 0.12065 -0.3048)
			(end 0.67945 -0.3048)
			(stroke
				(width 0.1)
				(type default)
			)
			(layer "F.Fab")
		)
		(fp_line
			(start 0.12065 -0.2794)
			(end 0.12065 -0.3048)
			(stroke
				(width 0.1)
				(type default)
			)
			(layer "F.Fab")
		)
		(fp_line
			(start 0.67945 -0.3048)
			(end 0.67945 0.3048)
			(stroke
				(width 0.1)
				(type default)
			)
			(layer "F.Fab")
		)
		(fp_line
			(start 0.67945 0.3048)
			(end 0.120396 0.3048)
			(stroke
				(width 0.1)
				(type default)
			)
			(layer "F.Fab")
		)
		(pad "1" smd circle
			(at -0.40005 0)
			(size 0 0)
			(layers "F.Cu" "F.Mask" "F.Paste")
			(net "PVDDIO_P1")
		)
		(pad "2" smd circle
			(at 0.40005 0)
			(size 0 0)
			(layers "F.Cu" "F.Mask" "F.Paste")
			(net "GND")
		)
	)
	(footprint ""
		(layer "F.Cu")
		(at 62.48273 -40.031162)
		(property "Reference" "Q119"
			(at -1.424432 -2.13614 0)
			(unlocked yes)
			(layer "F.SilkS")
			(effects
				(font
					(size 0.7874 0.5842)
					(thickness 0.1524)
				)
				(justify left)
			)
		)
		(property "Value" ""
			(at 0 0 0)
			(layer "F.Fab")
			(effects
				(font
					(size 1.27 1.27)
				)
			)
		)
		(duplicate_pad_numbers_are_jumpers no)
		(fp_line
			(start -1.332738 -1.100074)
			(end -0.4826 -1.100074)
			(stroke
				(width 0.1524)
				(type default)
			)
			(layer "F.SilkS")
		)
		(fp_line
			(start -1.332738 1.100074)
			(end -1.332738 -1.100074)
			(stroke
				(width 0.1524)
				(type default)
			)
			(layer "F.SilkS")
		)
		(fp_line
			(start -0.4826 -1.100074)
			(end 0 -0.541274)
			(stroke
				(width 0.1524)
				(type default)
			)
			(layer "F.SilkS")
		)
		(fp_line
			(start 0 -0.541274)
			(end 0.4826 -1.100074)
			(stroke
				(width 0.1524)
				(type default)
			)
			(layer "F.SilkS")
		)
		(fp_line
			(start 0.4826 -1.100074)
			(end 1.332738 -1.100074)
			(stroke
				(width 0.1524)
				(type default)
			)
			(layer "F.SilkS")
		)
		(fp_line
			(start 1.332738 -1.100074)
			(end 1.332738 1.100074)
			(stroke
				(width 0.1524)
				(type default)
			)
			(layer "F.SilkS")
		)
		(fp_line
			(start 1.332738 1.100074)
			(end -1.332738 1.100074)
			(stroke
				(width 0.1524)
				(type default)
			)
			(layer "F.SilkS")
		)
		(fp_poly
			(pts
				(xy -1.533144 -0.649986) (xy -2.2352 -0.298958) (xy -2.2352 -1.001014)
			)
			(stroke
				(width 0)
				(type default)
			)
			(fill yes)
			(layer "F.SilkS")
		)
		(fp_line
			(start -0.674878 -1.100074)
			(end 0.674878 -1.100074)
			(stroke
				(width 0.1)
				(type default)
			)
			(layer "F.Fab")
		)
		(fp_line
			(start -0.674878 1.100074)
			(end -0.674878 -1.100074)
			(stroke
				(width 0.1)
				(type default)
			)
			(layer "F.Fab")
		)
		(fp_line
			(start 0.674878 -1.100074)
			(end 0.674878 1.100074)
			(stroke
				(width 0.1)
				(type default)
			)
			(layer "F.Fab")
		)
		(fp_line
			(start 0.674878 1.100074)
			(end -0.674878 1.100074)
			(stroke
				(width 0.1)
				(type default)
			)
			(layer "F.Fab")
		)
		(fp_poly
			(pts
				(xy -2.2352 -0.298958) (xy -2.2352 -1.001014) (xy -1.533144 -0.649986)
			)
			(stroke
				(width 0)
				(type default)
			)
			(fill yes)
			(layer "F.Fab")
		)
		(pad "1" smd rect
			(at -0.94996 -0.649986 90)
			(size 0.4318 0.508)
			(layers "F.Cu" "F.Mask" "F.Paste")
			(net "GND")
		)
		(pad "2" smd rect
			(at -0.94996 0 90)
			(size 0.4318 0.508)
			(layers "F.Cu" "F.Mask" "F.Paste")
			(net "P3V3_OCP_EN_2_R")
		)
		(pad "3" smd rect
			(at -0.94996 0.649986 90)
			(size 0.4318 0.508)
			(layers "F.Cu" "F.Mask" "F.Paste")
			(net "P3V3_OCP_UV_2_R1")
		)
		(pad "4" smd rect
			(at 0.94996 0.649986 90)
			(size 0.4318 0.508)
			(layers "F.Cu" "F.Mask" "F.Paste")
			(net "GND")
		)
		(pad "5" smd rect
			(at 0.94996 0 90)
			(size 0.4318 0.508)
			(layers "F.Cu" "F.Mask" "F.Paste")
			(net "P3V3_OCP_2_EN_G")
		)
		(pad "6" smd rect
			(at 0.94996 -0.649986 90)
			(size 0.4318 0.508)
			(layers "F.Cu" "F.Mask" "F.Paste")
			(net "P3V3_OCP_2_EN_G")
		)
	)
	(footprint ""
		(layer "F.Cu")
		(at 154.293824 -191.358266 -90)
		(property "Reference" "R3355"
			(at 0 0 270)
			(layer "F.SilkS")
			(hide yes)
			(effects
				(font
					(size 1.27 1.27)
				)
			)
		)
		(property "Value" ""
			(at 0 0 270)
			(layer "F.Fab")
			(effects
				(font
					(size 1.27 1.27)
				)
			)
		)
		(duplicate_pad_numbers_are_jumpers no)
		(fp_line
			(start 0.324866 0.4064)
			(end -0.386334 0.4064)
			(stroke
				(width 0.1524)
				(type default)
			)
			(layer "F.SilkS")
		)
		(fp_line
			(start -0.7874 -0.011176)
			(end -0.7874 -0.4064)
			(stroke
				(width 0.1524)
				(type default)
			)
			(layer "F.SilkS")
		)
		(fp_line
			(start -0.7874 -0.4064)
			(end 0.7874 -0.4064)
			(stroke
				(width 0.1524)
				(type default)
			)
			(layer "F.SilkS")
		)
		(fp_line
			(start 0.7874 -0.4064)
			(end 0.7874 -0.011176)
			(stroke
				(width 0.1524)
				(type default)
			)
			(layer "F.SilkS")
		)
		(fp_line
			(start -0.67945 0.3048)
			(end -0.67945 -0.305054)
			(stroke
				(width 0.1)
				(type default)
			)
			(layer "F.Fab")
		)
		(fp_line
			(start -0.12065 0.3048)
			(end -0.67945 0.3048)
			(stroke
				(width 0.1)
				(type default)
			)
			(layer "F.Fab")
		)
		(fp_line
			(start 0.120396 0.3048)
			(end 0.120396 0.2794)
			(stroke
				(width 0.1)
				(type default)
			)
			(layer "F.Fab")
		)
		(fp_line
			(start 0.67945 0.3048)
			(end 0.120396 0.3048)
			(stroke
				(width 0.1)
				(type default)
			)
			(layer "F.Fab")
		)
		(fp_line
			(start -0.12065 0.2794)
			(end -0.12065 0.3048)
			(stroke
				(width 0.1)
				(type default)
			)
			(layer "F.Fab")
		)
		(fp_line
			(start 0.120396 0.2794)
			(end -0.12065 0.2794)
			(stroke
				(width 0.1)
				(type default)
			)
			(layer "F.Fab")
		)
		(fp_line
			(start -0.12065 -0.2794)
			(end 0.12065 -0.2794)
			(stroke
				(width 0.1)
				(type default)
			)
			(layer "F.Fab")
		)
		(fp_line
			(start 0.12065 -0.2794)
			(end 0.12065 -0.3048)
			(stroke
				(width 0.1)
				(type default)
			)
			(layer "F.Fab")
		)
		(fp_line
			(start 0.12065 -0.3048)
			(end 0.67945 -0.3048)
			(stroke
				(width 0.1)
				(type default)
			)
			(layer "F.Fab")
		)
		(fp_line
			(start 0.67945 -0.3048)
			(end 0.67945 0.3048)
			(stroke
				(width 0.1)
				(type default)
			)
			(layer "F.Fab")
		)
		(fp_line
			(start -0.67945 -0.305054)
			(end -0.12065 -0.305054)
			(stroke
				(width 0.1)
				(type default)
			)
			(layer "F.Fab")
		)
		(fp_line
			(start -0.12065 -0.305054)
			(end -0.12065 -0.2794)
			(stroke
				(width 0.1)
				(type default)
			)
			(layer "F.Fab")
		)
		(pad "1" smd circle
			(at -0.40005 0 270)
			(size 0 0)
			(layers "F.Cu" "F.Mask" "F.Paste")
			(net "CLK_100M_CPU1_CLK01_R_DN")
		)
		(pad "2" smd circle
			(at 0.40005 0 270)
			(size 0 0)
			(layers "F.Cu" "F.Mask" "F.Paste")
			(net "CLK_100M_CPU1_CLK01_DN")
		)
	)
	(footprint ""
		(layer "F.Cu")
		(at 13.621258 -427.098206 180)
		(property "Reference" "R6168"
			(at 0 0 180)
			(layer "F.SilkS")
			(hide yes)
			(effects
				(font
					(size 1.27 1.27)
				)
			)
		)
		(property "Value" ""
			(at 0 0 180)
			(layer "F.Fab")
			(effects
				(font
					(size 1.27 1.27)
				)
			)
		)
		(duplicate_pad_numbers_are_jumpers no)
		(fp_line
			(start 0.7874 0.4064)
			(end -0.7874 0.4064)
			(stroke
				(width 0.1524)
				(type default)
			)
			(layer "F.SilkS")
		)
		(fp_line
			(start 0.7874 -0.4064)
			(end 0.7874 0.4064)
			(stroke
				(width 0.1524)
				(type default)
			)
			(layer "F.SilkS")
		)
		(fp_line
			(start -0.7874 0.4064)
			(end -0.7874 -0.4064)
			(stroke
				(width 0.1524)
				(type default)
			)
			(layer "F.SilkS")
		)
		(fp_line
			(start -0.7874 -0.4064)
			(end 0.7874 -0.4064)
			(stroke
				(width 0.1524)
				(type default)
			)
			(layer "F.SilkS")
		)
		(fp_line
			(start 0.67945 0.3048)
			(end 0.120396 0.3048)
			(stroke
				(width 0.1)
				(type default)
			)
			(layer "F.Fab")
		)
		(fp_line
			(start 0.67945 -0.3048)
			(end 0.67945 0.3048)
			(stroke
				(width 0.1)
				(type default)
			)
			(layer "F.Fab")
		)
		(fp_line
			(start 0.12065 -0.2794)
			(end 0.12065 -0.3048)
			(stroke
				(width 0.1)
				(type default)
			)
			(layer "F.Fab")
		)
		(fp_line
			(start 0.12065 -0.3048)
			(end 0.67945 -0.3048)
			(stroke
				(width 0.1)
				(type default)
			)
			(layer "F.Fab")
		)
		(fp_line
			(start 0.120396 0.3048)
			(end 0.120396 0.2794)
			(stroke
				(width 0.1)
				(type default)
			)
			(layer "F.Fab")
		)
		(fp_line
			(start 0.120396 0.2794)
			(end -0.12065 0.2794)
			(stroke
				(width 0.1)
				(type default)
			)
			(layer "F.Fab")
		)
		(fp_line
			(start -0.12065 0.3048)
			(end -0.67945 0.3048)
			(stroke
				(width 0.1)
				(type default)
			)
			(layer "F.Fab")
		)
		(fp_line
			(start -0.12065 0.2794)
			(end -0.12065 0.3048)
			(stroke
				(width 0.1)
				(type default)
			)
			(layer "F.Fab")
		)
		(fp_line
			(start -0.12065 -0.2794)
			(end 0.12065 -0.2794)
			(stroke
				(width 0.1)
				(type default)
			)
			(layer "F.Fab")
		)
		(fp_line
			(start -0.12065 -0.305054)
			(end -0.12065 -0.2794)
			(stroke
				(width 0.1)
				(type default)
			)
			(layer "F.Fab")
		)
		(fp_line
			(start -0.67945 0.3048)
			(end -0.67945 -0.305054)
			(stroke
				(width 0.1)
				(type default)
			)
			(layer "F.Fab")
		)
		(fp_line
			(start -0.67945 -0.305054)
			(end -0.12065 -0.305054)
			(stroke
				(width 0.1)
				(type default)
			)
			(layer "F.Fab")
		)
		(pad "1" smd circle
			(at -0.40005 0 180)
			(size 0 0)
			(layers "F.Cu" "F.Mask" "F.Paste")
			(net "FM_P2E_BUF2_VODB_DB")
		)
		(pad "2" smd circle
			(at 0.40005 0 180)
			(size 0 0)
			(layers "F.Cu" "F.Mask" "F.Paste")
			(net "GND")
		)
	)
)
